(kicad_pcb
	(version 20241229)
	(generator "pcbnew")
	(generator_version "9.0")
	(general
		(thickness 1.6642)
		(legacy_teardrops no)
	)
	(paper "A3")
	(title_block
		(title "PolarFire SoM")
		(date "2025-07-22")
		(rev "1.1.4")
		(company "Antmicro Ltd")
		(comment 1 "www.antmicro.com")
		(comment 9 "footprints 111-114 of 470")
	)
	(layers
		(0 "F.Cu" mixed)
		(4 "In1.Cu" power)
		(6 "In2.Cu" signal)
		(8 "In3.Cu" power)
		(10 "In4.Cu" signal)
		(12 "In5.Cu" power)
		(14 "In6.Cu" power)
		(16 "In7.Cu" signal)
		(18 "In8.Cu" power)
		(20 "In9.Cu" signal)
		(22 "In10.Cu" power)
		(24 "In11.Cu" signal)
		(26 "In12.Cu" signal)
		(2 "B.Cu" mixed)
		(9 "F.Adhes" user "F.Adhesive")
		(11 "B.Adhes" user "B.Adhesive")
		(13 "F.Paste" user)
		(15 "B.Paste" user)
		(5 "F.SilkS" user "F.Silkscreen")
		(7 "B.SilkS" user "B.Silkscreen")
		(1 "F.Mask" user)
		(3 "B.Mask" user)
		(17 "Dwgs.User" user "User.Drawings")
		(19 "Cmts.User" user "User.Comments")
		(21 "Eco1.User" user "User.Eco1")
		(23 "Eco2.User" user "User.Eco2")
		(25 "Edge.Cuts" user)
		(27 "Margin" user)
		(31 "F.CrtYd" user "F.Courtyard")
		(29 "B.CrtYd" user "B.Courtyard")
		(35 "F.Fab" user)
		(33 "B.Fab" user)
	)
	(footprint "antmicro-footprints:FB_0402_1005Metric"
		(layer "F.Cu")
		(at 208.085 143.85)
		(descr "Ferrite Bead SMD 0402")
		(tags "ferrite bead SMD 0402")
		(property "Reference" "FB5"
			(at -8.085 10.465 90)
			(layer "F.SilkS")
			(effects
				(font
					(size 0.7 0.7)
					(thickness 0.15)
				)
				(justify left bottom)
			)
		)
		(property "Value" "FB_120Z_1.2A_TDK-MPZ_0402"
			(at 0 1.4 0)
			(layer "F.Fab")
			(hide yes)
			(effects
				(font
					(size 0.7 0.7)
					(thickness 0.15)
				)
				(justify left bottom)
			)
		)
		(property "Datasheet" "https://product.tdk.com/en/search/emc/emc/beads/info?part_no=MPZ1005S121CT000"
			(at 0 0 0)
			(layer "F.Fab")
			(hide yes)
			(effects
				(font
					(size 1.27 1.27)
					(thickness 0.15)
				)
			)
		)
		(property "Description" "Ferrite Bead, 0402 [1005 Metric], 120 ohm, 1.2A, MPZ, 0.06 ohm, ± 25%, DC Power line"
			(at 0 0 0)
			(layer "F.Fab")
			(hide yes)
			(effects
				(font
					(size 1.27 1.27)
					(thickness 0.15)
				)
			)
		)
		(property "Author" "Antmicro"
			(at 0 0 0)
			(layer "F.Fab")
			(hide yes)
			(effects
				(font
					(size 1 1)
					(thickness 0.15)
				)
			)
		)
		(property "Current" ""
			(at 0 0 0)
			(layer "F.Fab")
			(hide yes)
			(effects
				(font
					(size 1 1)
					(thickness 0.15)
				)
			)
		)
		(property "License" "Apache-2.0"
			(at 0 0 0)
			(layer "F.Fab")
			(hide yes)
			(effects
				(font
					(size 1 1)
					(thickness 0.15)
				)
			)
		)
		(property "MPN" "MPZ1005S121CT000"
			(at 0 0 0)
			(layer "F.Fab")
			(hide yes)
			(effects
				(font
					(size 1 1)
					(thickness 0.15)
				)
			)
		)
		(property "Manufacturer" "TDK"
			(at 0 0 0)
			(layer "F.Fab")
			(hide yes)
			(effects
				(font
					(size 1 1)
					(thickness 0.15)
				)
			)
		)
		(property "Public" ""
			(at 0 0 0)
			(layer "F.Fab")
			(hide yes)
			(effects
				(font
					(size 1 1)
					(thickness 0.15)
				)
			)
		)
		(property "Val" "120Z/1.2A"
			(at 0 0 0)
			(layer "F.Fab")
			(hide yes)
			(effects
				(font
					(size 1 1)
					(thickness 0.15)
				)
			)
		)
		(sheetname "/MIPI CrossLink/")
		(sheetfile "crosslink.kicad_sch")
		(attr smd)
		(fp_rect
			(start -0.925 -0.47)
			(end 0.925 0.47)
			(stroke
				(width 0.05)
				(type default)
			)
			(fill no)
			(layer "F.CrtYd")
		)
		(fp_rect
			(start -0.5 -0.25)
			(end 0.5 0.25)
			(stroke
				(width 0.15)
				(type solid)
			)
			(fill no)
			(layer "F.Fab")
		)
		(fp_text user "${REFERENCE}"
			(at -0.95 3.168 0)
			(layer "F.Fab")
			(effects
				(font
					(size 0.7 0.7)
					(thickness 0.15)
				)
				(justify left bottom)
			)
		)
		(fp_text user "License: Apache-2.0"
			(at -0.95 5.169 0)
			(layer "F.Fab")
			(effects
				(font
					(size 0.7 0.7)
					(thickness 0.15)
				)
				(justify left bottom)
			)
		)
		(fp_text user "Author: Antmicro"
			(at -0.95 4.169 0)
			(layer "F.Fab")
			(effects
				(font
					(size 0.7 0.7)
					(thickness 0.15)
				)
				(justify left bottom)
			)
		)
		(pad "1" smd roundrect
			(at -0.48 0)
			(size 0.59 0.64)
			(layers "F.Cu" "F.Mask" "F.Paste")
			(roundrect_rratio 0.25)
			(net 191 "/MIPI CrossLink/CL_VCCIO2")
			(pintype "passive")
		)
		(pad "2" smd roundrect
			(at 0.48 0)
			(size 0.59 0.64)
			(layers "F.Cu" "F.Mask" "F.Paste")
			(roundrect_rratio 0.25)
			(net 237 "1V8_CL")
			(pintype "passive")
		)
	)
	(footprint "antmicro-footprints:FB_0402_1005Metric"
		(layer "F.Cu")
		(at 208.085 150.72)
		(descr "Ferrite Bead SMD 0402")
		(tags "ferrite bead SMD 0402")
		(property "Reference" "FB10"
			(at -1.214999 3.595 90)
			(layer "F.SilkS")
			(effects
				(font
					(size 0.7 0.7)
					(thickness 0.15)
				)
				(justify left bottom)
			)
		)
		(property "Value" "FB_120Z_1.2A_TDK-MPZ_0402"
			(at 0 1.4 0)
			(layer "F.Fab")
			(hide yes)
			(effects
				(font
					(size 0.7 0.7)
					(thickness 0.15)
				)
				(justify left bottom)
			)
		)
		(property "Datasheet" "https://product.tdk.com/en/search/emc/emc/beads/info?part_no=MPZ1005S121CT000"
			(at 0 0 0)
			(layer "F.Fab")
			(hide yes)
			(effects
				(font
					(size 1.27 1.27)
					(thickness 0.15)
				)
			)
		)
		(property "Description" "Ferrite Bead, 0402 [1005 Metric], 120 ohm, 1.2A, MPZ, 0.06 ohm, ± 25%, DC Power line"
			(at 0 0 0)
			(layer "F.Fab")
			(hide yes)
			(effects
				(font
					(size 1.27 1.27)
					(thickness 0.15)
				)
			)
		)
		(property "Author" "Antmicro"
			(at 0 0 0)
			(layer "F.Fab")
			(hide yes)
			(effects
				(font
					(size 1 1)
					(thickness 0.15)
				)
			)
		)
		(property "Current" ""
			(at 0 0 0)
			(layer "F.Fab")
			(hide yes)
			(effects
				(font
					(size 1 1)
					(thickness 0.15)
				)
			)
		)
		(property "License" "Apache-2.0"
			(at 0 0 0)
			(layer "F.Fab")
			(hide yes)
			(effects
				(font
					(size 1 1)
					(thickness 0.15)
				)
			)
		)
		(property "MPN" "MPZ1005S121CT000"
			(at 0 0 0)
			(layer "F.Fab")
			(hide yes)
			(effects
				(font
					(size 1 1)
					(thickness 0.15)
				)
			)
		)
		(property "Manufacturer" "TDK"
			(at 0 0 0)
			(layer "F.Fab")
			(hide yes)
			(effects
				(font
					(size 1 1)
					(thickness 0.15)
				)
			)
		)
		(property "Public" ""
			(at 0 0 0)
			(layer "F.Fab")
			(hide yes)
			(effects
				(font
					(size 1 1)
					(thickness 0.15)
				)
			)
		)
		(property "Val" "120Z/1.2A"
			(at 0 0 0)
			(layer "F.Fab")
			(hide yes)
			(effects
				(font
					(size 1 1)
					(thickness 0.15)
				)
			)
		)
		(sheetname "/MIPI CrossLink/")
		(sheetfile "crosslink.kicad_sch")
		(attr smd)
		(fp_rect
			(start -0.925 -0.47)
			(end 0.925 0.47)
			(stroke
				(width 0.05)
				(type default)
			)
			(fill no)
			(layer "F.CrtYd")
		)
		(fp_rect
			(start -0.5 -0.25)
			(end 0.5 0.25)
			(stroke
				(width 0.15)
				(type solid)
			)
			(fill no)
			(layer "F.Fab")
		)
		(fp_text user "License: Apache-2.0"
			(at -0.95 5.169 0)
			(layer "F.Fab")
			(effects
				(font
					(size 0.7 0.7)
					(thickness 0.15)
				)
				(justify left bottom)
			)
		)
		(fp_text user "Author: Antmicro"
			(at -0.95 4.169 0)
			(layer "F.Fab")
			(effects
				(font
					(size 0.7 0.7)
					(thickness 0.15)
				)
				(justify left bottom)
			)
		)
		(fp_text user "${REFERENCE}"
			(at -0.95 3.168 0)
			(layer "F.Fab")
			(effects
				(font
					(size 0.7 0.7)
					(thickness 0.15)
				)
				(justify left bottom)
			)
		)
		(pad "1" smd roundrect
			(at -0.48 0)
			(size 0.59 0.64)
			(layers "F.Cu" "F.Mask" "F.Paste")
			(roundrect_rratio 0.25)
			(net 204 "/MIPI CrossLink/CL_VCCPLL_DPHY0")
			(pintype "passive")
		)
		(pad "2" smd roundrect
			(at 0.48 0)
			(size 0.59 0.64)
			(layers "F.Cu" "F.Mask" "F.Paste")
			(roundrect_rratio 0.25)
			(net 96 "+1V2")
			(pintype "passive")
		)
	)
	(footprint "antmicro-footprints:W-PDFN-8-1EP_8x6mm_P1.27mm_EP4.3x3.4mm"
		(layer "F.Cu")
		(at 224.22 129.37 90)
		(property "Reference" "U3"
			(at 4.07 -3.67 0)
			(layer "F.SilkS")
			(effects
				(font
					(size 0.7 0.7)
					(thickness 0.15)
				)
				(justify left bottom)
			)
		)
		(property "Value" "MT25QL01GBBB1EW9-0SIT"
			(at -0.005 3.653 90)
			(layer "F.Fab")
			(hide yes)
			(effects
				(font
					(size 0.7 0.7)
					(thickness 0.15)
				)
				(justify left bottom)
			)
		)
		(property "Datasheet" "https://www.mouser.com/datasheet/2/671/mict_s_a0002234966_1-2290738.pdf"
			(at 0 0 90)
			(layer "F.Fab")
			(hide yes)
			(effects
				(font
					(size 1.27 1.27)
					(thickness 0.15)
				)
			)
		)
		(property "Description" "NOR Flash Serial-SPI 3.3V 1G-bit 1G/512M/256M x 1/2-bit/4-bit 6ns 16-Pin SOP-II T/R"
			(at 0 0 90)
			(layer "F.Fab")
			(hide yes)
			(effects
				(font
					(size 1.27 1.27)
					(thickness 0.15)
				)
			)
		)
		(property "Author" "Antmicro"
			(at 353.59 -94.85 0)
			(layer "F.Fab")
			(hide yes)
			(effects
				(font
					(size 1 1)
					(thickness 0.15)
				)
			)
		)
		(property "License" "Apache-2.0"
			(at 353.59 -94.85 0)
			(layer "F.Fab")
			(hide yes)
			(effects
				(font
					(size 1 1)
					(thickness 0.15)
				)
			)
		)
		(property "MPN" "MT25QL01GBBB1EW9-0SIT"
			(at 353.59 -94.85 0)
			(layer "F.Fab")
			(hide yes)
			(effects
				(font
					(size 1 1)
					(thickness 0.15)
				)
			)
		)
		(property "Manufacturer" "Micron Technology"
			(at 353.59 -94.85 0)
			(layer "F.Fab")
			(hide yes)
			(effects
				(font
					(size 1 1)
					(thickness 0.15)
				)
			)
		)
		(property "VSD_class" "SPI Flash"
			(at 353.59 -94.85 0)
			(layer "F.Fab")
			(hide yes)
			(effects
				(font
					(size 1 1)
					(thickness 0.15)
				)
			)
		)
		(sheetname "/FPGA Config/")
		(sheetfile "fpga-config.kicad_sch")
		(attr smd)
		(fp_line
			(start -4.3 -2.997)
			(end 3.995 -2.997)
			(stroke
				(width 0.15)
				(type solid)
			)
			(layer "F.SilkS")
		)
		(fp_line
			(start -3.995 3.003)
			(end 3.995 3.003)
			(stroke
				(width 0.15)
				(type solid)
			)
			(layer "F.SilkS")
		)
		(fp_circle
			(center -4.4 -2.6)
			(end -4.35 -2.6)
			(stroke
				(width 0.15)
				(type solid)
			)
			(fill yes)
			(layer "F.SilkS")
		)
		(fp_rect
			(start -4.38 -3.25)
			(end 4.37 3.25)
			(stroke
				(width 0.05)
				(type solid)
			)
			(fill no)
			(layer "F.CrtYd")
		)
		(fp_text user "License: Apache-2.0"
			(at -4.73 6.853 90)
			(layer "F.Fab")
			(effects
				(font
					(size 0.7 0.7)
					(thickness 0.15)
				)
				(justify left bottom)
			)
		)
		(fp_text user "${REFERENCE}"
			(at -4.73 8.053 90)
			(layer "F.Fab")
			(effects
				(font
					(size 0.7 0.7)
					(thickness 0.15)
				)
				(justify left bottom)
			)
		)
		(fp_text user "Author: Antmicro"
			(at -4.73 5.653 90)
			(layer "F.Fab")
			(effects
				(font
					(size 0.7 0.7)
					(thickness 0.15)
				)
				(justify left bottom)
			)
		)
		(pad "" smd rect
			(at -1.03 -1.47)
			(size 0.8 0.8)
			(layers "F.Paste")
		)
		(pad "" smd rect
			(at -1.03 -0.47)
			(size 0.8 0.8)
			(layers "F.Paste")
		)
		(pad "" smd rect
			(at -1.03 0.53)
			(size 0.8 0.8)
			(layers "F.Paste")
		)
		(pad "" smd rect
			(at -1.03 1.53)
			(size 0.8 0.8)
			(layers "F.Paste")
		)
		(pad "" smd rect
			(at -0.03 -1.47)
			(size 0.8 0.8)
			(layers "F.Paste")
		)
		(pad "" smd rect
			(at -0.03 -0.47)
			(size 0.8 0.8)
			(layers "F.Paste")
		)
		(pad "" smd rect
			(at -0.03 0.53)
			(size 0.8 0.8)
			(layers "F.Paste")
		)
		(pad "" smd rect
			(at -0.03 1.53)
			(size 0.8 0.8)
			(layers "F.Paste")
		)
		(pad "" smd rect
			(at 0.97 -1.47)
			(size 0.8 0.8)
			(layers "F.Paste")
		)
		(pad "" smd rect
			(at 0.97 -0.47)
			(size 0.8 0.8)
			(layers "F.Paste")
		)
		(pad "" smd rect
			(at 0.97 0.53)
			(size 0.8 0.8)
			(layers "F.Paste")
		)
		(pad "" smd rect
			(at 0.97 1.53)
			(size 0.8 0.8)
			(layers "F.Paste")
		)
		(pad "1" smd roundrect
			(at -3.905 -1.9)
			(size 0.45 0.95)
			(layers "F.Cu" "F.Mask" "F.Paste")
			(roundrect_rratio 0.25)
			(net 288 "/FPGA Config/Flash.CS")
			(pinfunction "S#")
			(pintype "input")
		)
		(pad "2" smd roundrect
			(at -3.905 -0.63)
			(size 0.45 0.95)
			(layers "F.Cu" "F.Mask" "F.Paste")
			(roundrect_rratio 0.25)
			(net 290 "/FPGA Config/Flash.MISO")
			(pinfunction "DQ1")
			(pintype "bidirectional")
		)
		(pad "3" smd roundrect
			(at -3.905 0.64)
			(size 0.45 0.95)
			(layers "F.Cu" "F.Mask" "F.Paste")
			(roundrect_rratio 0.25)
			(net 258 "Net-(U3-W#{slash}DQ2)")
			(pinfunction "W#/DQ2")
			(pintype "bidirectional")
		)
		(pad "4" smd roundrect
			(at -3.905 1.91)
			(size 0.45 0.95)
			(layers "F.Cu" "F.Mask" "F.Paste")
			(roundrect_rratio 0.25)
			(net 417 "GND")
			(pinfunction "GND")
			(pintype "power_in")
		)
		(pad "5" smd roundrect
			(at 3.895 1.91)
			(size 0.45 0.95)
			(layers "F.Cu" "F.Mask" "F.Paste")
			(roundrect_rratio 0.25)
			(net 287 "/FPGA Config/Flash.MOSI")
			(pinfunction "DQ0")
			(pintype "bidirectional")
		)
		(pad "6" smd roundrect
			(at 3.895 0.64)
			(size 0.45 0.95)
			(layers "F.Cu" "F.Mask" "F.Paste")
			(roundrect_rratio 0.25)
			(net 286 "/FPGA Config/Flash.CLK")
			(pinfunction "C")
			(pintype "input")
		)
		(pad "7" smd roundrect
			(at 3.895 -0.63)
			(size 0.45 0.95)
			(layers "F.Cu" "F.Mask" "F.Paste")
			(roundrect_rratio 0.25)
			(net 259 "Net-(U3-HOLD#{slash}DQ3)")
			(pinfunction "HOLD#/DQ3")
			(pintype "bidirectional")
		)
		(pad "8" smd roundrect
			(at 3.895 -1.9)
			(size 0.45 0.95)
			(layers "F.Cu" "F.Mask" "F.Paste")
			(roundrect_rratio 0.25)
			(net 50 "+3V3")
			(pinfunction "VCC")
			(pintype "power_in")
		)
		(pad "9" smd roundrect
			(at -0.005 0.005)
			(size 4.3 3.4)
			(layers "F.Cu" "F.Mask")
			(roundrect_rratio 0)
			(chamfer_ratio 0.1)
			(chamfer bottom_left)
		)
	)
	(footprint "antmicro-footprints:Fiducial_1mm_Mask2mm"
		(layer "F.Cu")
		(at 228.05 122)
		(descr "Circular Fiducial, 1mm bare copper, 3mm soldermask opening")
		(tags "fiducial")
		(property "Reference" "FD3"
			(at 0 -1.4 0)
			(layer "F.SilkS")
			(hide yes)
			(effects
				(font
					(size 0.7 0.7)
					(thickness 0.15)
				)
				(justify left bottom)
			)
		)
		(property "Value" "Fiducial_1mm_Mask2mm"
			(at 0 2.2 0)
			(layer "F.Fab")
			(hide yes)
			(effects
				(font
					(size 0.7 0.7)
					(thickness 0.15)
				)
				(justify left bottom)
			)
		)
		(property "Description" "Fiducial mask "
			(at 0 0 0)
			(layer "F.Fab")
			(hide yes)
			(effects
				(font
					(size 1.27 1.27)
					(thickness 0.15)
				)
			)
		)
		(property "Author" "Antmicro"
			(at 0 0 0)
			(layer "F.Fab")
			(hide yes)
			(effects
				(font
					(size 1 1)
					(thickness 0.15)
				)
			)
		)
		(property "License" "Apache-2.0"
			(at 0 0 0)
			(layer "F.Fab")
			(hide yes)
			(effects
				(font
					(size 1 1)
					(thickness 0.15)
				)
			)
		)
		(property "exclude_from_bom" ""
			(at 0 0 0)
			(layer "F.Fab")
			(hide yes)
			(effects
				(font
					(size 1 1)
					(thickness 0.15)
				)
			)
		)
		(sheetfile "polarfire-som.kicad_sch")
		(attr board_only exclude_from_pos_files exclude_from_bom)
		(fp_circle
			(center 0 0)
			(end 1.24 0)
			(stroke
				(width 0.05)
				(type solid)
			)
			(fill no)
			(layer "F.CrtYd")
		)
		(fp_circle
			(center 0 0)
			(end 0.999 0)
			(stroke
				(width 0.15)
				(type solid)
			)
			(fill no)
			(layer "F.Fab")
		)
		(fp_text user "License: Apache-2.0"
			(at -1.25 7.003 0)
			(layer "F.Fab")
			(effects
				(font
					(size 0.7 0.7)
					(thickness 0.15)
				)
				(justify left bottom)
			)
		)
		(fp_text user "${REFERENCE}"
			(at -1.25 4.603 0)
			(layer "F.Fab")
			(effects
				(font
					(size 0.7 0.7)
					(thickness 0.15)
				)
				(justify left bottom)
			)
		)
		(fp_text user "Author: Antmicro"
			(at -1.25 5.803 0)
			(layer "F.Fab")
			(effects
				(font
					(size 0.7 0.7)
					(thickness 0.15)
				)
				(justify left bottom)
			)
		)
		(pad "" smd circle
			(at 0 0)
			(size 1 1)
			(layers "F.Cu" "F.Mask")
			(solder_mask_margin 0.5)
			(clearance 0.5)
		)
	)
)
